#ISCELL
  mstr_misc dns *
  *
#ISCELL
  pure_quanta quanta_title_block_c *
  *
#ISCELL
  pure_quanta_power universal_gnd *
  page178_i1
#CELL
  pure_quanta q_cap *
  page178_i10
#CELL
  pure_quanta q_cap *
  page178_i11
#ISCELL
  pure_quanta_power universal_gnd *
  page178_i12
#CELL
  pure_quanta q_res *
  page178_i13
#ISCELL
  pure_quanta_power universal_gnd *
  page178_i14
#CELL
  pure_quanta q_res *
  page178_i15
#ISCELL
  pure_quanta_power vcc_core *
  page178_i16
#ISCELL
  standard offpage *
  page178_i17
#ISCELL
  standard offpage *
  page178_i18
#ISCELL
  pure_quanta_power universal_gnd *
  page178_i19
#CELL
  pure_quanta q_cap *
  page178_i2
#CELL
  pure_quanta q_cap *
  page178_i20
#ISCELL
  pure_quanta_power universal_gnd *
  page178_i21
#CELL
  pure_quanta isl99390frztr5935 *
  page178_i22
#ISCELL
  pure_quanta_power universal_gnd *
  page178_i23
#ISCELL
  standard offpage *
  page178_i24
#ISCELL
  standard offpage *
  page178_i25
#ISCELL
  pure_quanta_power universal_gnd *
  page178_i26
#CELL
  pure_quanta q_cap *
  page178_i27
#CELL
  pure_quanta q_res *
  page178_i28
#ISCELL
  pure_quanta_power vcc_core *
  page178_i29
#ISCELL
  pure_quanta_power universal_gnd *
  page178_i3
#ISCELL
  pure_quanta_power universal_gnd *
  page178_i30
#CELL
  pure_quanta q_cap *
  page178_i31
#ISCELL
  pure_quanta_power universal_gnd *
  page178_i32
#CELL
  pure_quanta q_res *
  page178_i33
#ISCELL
  pure_quanta_power universal_gnd *
  page178_i34
#CELL
  pure_quanta q_res *
  page178_i35
#CELL
  pure_quanta q_inductor *
  page178_i36
#CELL
  pure_quanta q_cap *
  page178_i37
#CELL
  pure_quanta q_inductor4p_14 *
  page178_i38
#CELL
  pure_quanta q_res *
  page178_i39
#CELL
  pure_quanta q_res *
  page178_i4
#CELL
  pure_quanta q_cap *
  page178_i40
#CELL
  pure_quanta q_cap *
  page178_i41
#CELL
  pure_quanta q_cap *
  page178_i42
#ISCELL
  pure_quanta_power universal_gnd *
  page178_i43
#CELL
  pure_quanta q_res *
  page178_i44
#CELL
  pure_quanta q_cap *
  page178_i45
#ISCELL
  pure_quanta_power universal_gnd *
  page178_i46
#CELL
  pure_quanta q_cap *
  page178_i47
#ISCELL
  pure_quanta_power vcc_core *
  page178_i48
#CELL
  pure_quanta q_res *
  page178_i49
#ISCELL
  standard offpage *
  page178_i5
#ISCELL
  standard offpage *
  page178_i50
#CELL
  pure_quanta q_cap *
  page178_i51
#ISCELL
  pure_quanta_power universal_gnd *
  page178_i52
#CELL
  pure_quanta q_cap *
  page178_i53
#ISCELL
  pure_quanta_power vcc_core *
  page178_i54
#ISCELL
  pure_quanta_power universal_gnd *
  page178_i55
#CELL
  pure_quanta q_res *
  page178_i56
#CELL
  pure_quanta q_cap *
  page178_i57
#CELL
  pure_quanta q_cap *
  page178_i58
#CELL
  pure_quanta q_cap *
  page178_i59
#ISCELL
  standard offpage *
  page178_i6
#CELL
  pure_quanta q_cap *
  page178_i60
#ISCELL
  standard offpage *
  page178_i61
#CELL
  pure_quanta q_cap *
  page178_i62
#CELL
  pure_quanta q_inductor4p_14 *
  page178_i63
#ISCELL
  pure_quanta_power universal_gnd *
  page178_i64
#CELL
  pure_quanta q_cap *
  page178_i65
#CELL
  pure_quanta q_cap *
  page178_i66
#ISCELL
  pure_quanta_power vcc_core *
  page178_i67
#ISCELL
  standard offpage *
  page178_i68
#CELL
  pure_quanta q_cap *
  page178_i69
#ISCELL
  standard offpage *
  page178_i7
#CELL
  pure_quanta q_cap *
  page178_i70
#ISCELL
  pure_quanta_power vcc_core *
  page178_i71
#CELL
  pure_quanta q_cap *
  page178_i72
#CELL
  pure_quanta isl99390frztr5935 *
  page178_i73
#ISCELL
  standard offpage *
  page178_i8
#ISCELL
  pure_quanta_power universal_gnd *
  page178_i9
